# TIMECARD (Time Appliance Project (Time Card)) — schematic netlist excerpt (pin names and nets, part order shuffled) for the footprints in the layout excerpt that follows; sources: Cadence DE-HDL packaged netlist, KiCad conversion of R4006-B0001-02_R01.brd

SP68  NULL  pkg DUMMY  page 34
TP7  TP_PIONT  pkg TP010CT020B030_PTH  page 24 : \1\ = UNNAMED_524_FT4232HLREELQFP64_2
TP48  TP_PIONT  pkg TP010CT020B030_PTH  page 25 : \1\ = PCIE_CONN_PERST_N
R179  RESISTOR  4.7KOHM 1%  pkg SMC_0402R_H016  page 30 : \1\ = XP3R3V ; \2\ = XP1R8V_PG_R
SP20  SOLDER_PREFORM  pkg 0201_SOLDER_PREFORM_4MIL  page 34 : \1\ = NC ; \2\ = NC

(kicad_pcb
	(version 20260206)
	(generator "pcbnew")
	(generator_version "10.0")
	(general
		(thickness 1.6)
		(legacy_teardrops no)
	)
	(paper "A4")
	(title_block
		(title "timecard-production-celestica-r4006 — R4006-B0001-02_R01.brd")
		(comment 1 "Time Appliance Project (Time Card) / footprints 140-144 of 1113")
	)
	(layers
		(0 "F.Cu" signal "TOP")
		(4 "In1.Cu" signal "L02_GND1")
		(6 "In2.Cu" signal "L03_SIG1")
		(8 "In3.Cu" signal "L04_GND2")
		(10 "In4.Cu" signal "L05_VCC1")
		(12 "In5.Cu" signal "L06_VCC2")
		(14 "In6.Cu" signal "L07_GND3")
		(16 "In7.Cu" signal "L08_SIG2")
		(18 "In8.Cu" signal "L09_GND4")
		(2 "B.Cu" signal "BOTTOM")
		(9 "F.Adhes" user "F.Adhesive")
		(11 "B.Adhes" user "B.Adhesive")
		(13 "F.Paste" user "Package Geometry/Pastemask Top")
		(15 "B.Paste" user "Package Geometry/Pastemask Bottom")
		(5 "F.SilkS" user "Ref Des/Silkscreen Top")
		(7 "B.SilkS" user "Ref Des/Silkscreen Bottom")
		(1 "F.Mask" user "Board Geometry/Soldermask Top")
		(3 "B.Mask" user "Board Geometry/Soldermask Bottom")
		(17 "Dwgs.User" user "User.Drawings")
		(19 "Cmts.User" user "User.Comments")
		(21 "Eco1.User" user "User.Eco1")
		(23 "Eco2.User" user "User.Eco2")
		(25 "Edge.Cuts" user "Board Geometry/Outline")
		(27 "Margin" user)
		(31 "F.CrtYd" user "Package Geometry/Place Bound Top")
		(29 "B.CrtYd" user "Package Geometry/Place Bound Bottom")
		(35 "F.Fab" user "Ref Des/Assembly Top")
		(33 "B.Fab" user "Ref Des/Assembly Bottom")
	)
	(footprint ""
		(layer "F.Cu")
		(at 133.858 -70.866 -90)
		(property "Reference" "R179"
			(at -4.191 -1.05537 90)
			(unlocked yes)
			(layer "F.SilkS")
			(effects
				(font
					(size 0.7874 0.5842)
					(thickness 0.1524)
				)
			)
		)
		(property "Value" "VAL*"
			(at 0.02032 2.13233 270)
			(unlocked yes)
			(layer "F.Fab")
			(hide yes)
			(effects
				(font
					(size 0.7874 0.5842)
					(thickness 0.1524)
				)
			)
		)
		(property "Device Type" "RESISTOR-G155-14701-01,4.7KOHMA"
			(at 0.008382 1.210564 270)
			(unlocked yes)
			(layer "F.Fab")
			(hide yes)
			(effects
				(font
					(size 0.7874 0.5842)
					(thickness 0.1524)
				)
			)
		)
		(property "User Part Number" "PARTNUM*"
			(at 0.02032 4.024884 270)
			(unlocked yes)
			(layer "Cmts.User")
			(hide yes)
			(effects
				(font
					(size 0.7874 0.5842)
					(thickness 0.1524)
				)
			)
		)
		(property "Tolerance" "TOL*"
			(at 0.044704 3.05435 270)
			(unlocked yes)
			(layer "Cmts.User")
			(hide yes)
			(effects
				(font
					(size 0.7874 0.5842)
					(thickness 0.1524)
				)
			)
		)
		(duplicate_pad_numbers_are_jumpers no)
		(fp_line
			(start -1.143 0.5588)
			(end 1.143 0.5588)
			(stroke
				(width 0.1)
				(type default)
			)
			(layer "F.SilkS")
		)
		(fp_line
			(start 1.143 0.5588)
			(end 1.143 -0.5588)
			(stroke
				(width 0.1)
				(type default)
			)
			(layer "F.SilkS")
		)
		(fp_line
			(start -1.143 -0.5588)
			(end -1.143 0.5588)
			(stroke
				(width 0.1)
				(type default)
			)
			(layer "F.SilkS")
		)
		(fp_line
			(start 1.143 -0.5588)
			(end -1.143 -0.5588)
			(stroke
				(width 0.1)
				(type default)
			)
			(layer "F.SilkS")
		)
		(fp_rect
			(start -1.143 0.5588)
			(end 1.143 -0.5588)
			(stroke
				(width 0)
				(type default)
			)
			(fill no)
			(layer "F.CrtYd")
		)
		(fp_line
			(start -0.508 0.3048)
			(end 0.508 0.3048)
			(stroke
				(width 0.1)
				(type default)
			)
			(layer "F.Fab")
		)
		(fp_line
			(start 0.508 0.3048)
			(end 0.508 -0.3048)
			(stroke
				(width 0.1)
				(type default)
			)
			(layer "F.Fab")
		)
		(fp_line
			(start -0.508 -0.3048)
			(end -0.508 0.3048)
			(stroke
				(width 0.1)
				(type default)
			)
			(layer "F.Fab")
		)
		(fp_line
			(start 0.508 -0.3048)
			(end -0.508 -0.3048)
			(stroke
				(width 0.1)
				(type default)
			)
			(layer "F.Fab")
		)
		(pad "1" smd rect
			(at -0.5334 0 270)
			(size 0.7112 0.6096)
			(layers "F.Cu" "F.Mask" "F.Paste")
			(net "XP3R3V")
		)
		(pad "2" smd rect
			(at 0.5334 0 270)
			(size 0.7112 0.6096)
			(layers "F.Cu" "F.Mask" "F.Paste")
			(net "XP1R8V_PG_R")
		)
		(zone
			(layer "F.Cu")
			(hatch none 0.5)
			(connect_pads
				(clearance 0)
			)
			(min_thickness 0.25)
			(keepout
				(tracks allowed)
				(vias not_allowed)
				(pads allowed)
				(copperpour not_allowed)
				(footprints allowed)
			)
			(placement
				(enabled no)
				(sheetname "")
			)
			(fill
				(thermal_gap 0.5)
				(thermal_bridge_width 0.5)
				(island_removal_mode 0)
			)
			(polygon
				(pts
					(xy 133.5532 -70.9422) (xy 133.5532 -70.7898) (xy 134.1628 -70.7898) (xy 134.1628 -70.9422)
				)
			)
		)
	)
	(footprint ""
		(layer "F.Cu")
		(at 58.313828 -12.425172)
		(property "Reference" "TP48"
			(at -0.986028 -1.505458 0)
			(unlocked yes)
			(layer "F.SilkS")
			(effects
				(font
					(size 0.7874 0.5842)
					(thickness 0.1524)
				)
				(justify left)
			)
		)
		(property "Value" ""
			(at 0 0 0)
			(layer "F.Fab")
			(effects
				(font
					(size 1.27 1.27)
				)
			)
		)
		(property "Device Type" "TP_PIONT-TP010CT020B030_PTH-TPA"
			(at -1.341882 0.996696 0)
			(unlocked yes)
			(layer "F.Fab")
			(hide yes)
			(effects
				(font
					(size 0.7874 0.5842)
					(thickness 0.000001)
				)
				(justify left)
			)
		)
		(duplicate_pad_numbers_are_jumpers no)
		(fp_poly
			(pts
				(arc
					(start 0.889 0)
					(mid -0.889 0)
					(end 0.889 0)
				)
			)
			(stroke
				(width 0)
				(type default)
			)
			(fill no)
			(layer "B.CrtYd")
		)
		(fp_poly
			(pts
				(arc
					(start 0.889 0)
					(mid -0.889 0)
					(end 0.889 0)
				)
			)
			(stroke
				(width 0)
				(type default)
			)
			(fill no)
			(layer "F.CrtYd")
		)
		(pad "1" thru_hole circle
			(at 0 0)
			(size 0.508 0.508)
			(drill 0.254)
			(layers "*.Cu" "*.Mask")
			(remove_unused_layers no)
			(net "PCIE_CONN_PERST_N")
			(clearance 0.1016)
			(padstack
				(mode front_inner_back)
				(layer "Inner"
					(shape circle)
					(size 0.508 0.508)
					(clearance 0.1016)
				)
				(layer "B.Cu"
					(shape circle)
					(size 0.762 0.762)
					(clearance -0.0254)
				)
			)
		)
	)
	(footprint ""
		(layer "F.Cu")
		(at 22.225 -75.057)
		(property "Reference" "TP7"
			(at 0 0 0)
			(layer "F.SilkS")
			(hide yes)
			(effects
				(font
					(size 1.27 1.27)
				)
			)
		)
		(property "Value" ""
			(at 0 0 0)
			(layer "F.Fab")
			(effects
				(font
					(size 1.27 1.27)
				)
			)
		)
		(property "Device Type" "TP_PIONT-TP010CT020B030_PTH-TPA"
			(at -1.341882 0.996696 0)
			(unlocked yes)
			(layer "F.Fab")
			(hide yes)
			(effects
				(font
					(size 0.7874 0.5842)
					(thickness 0.1524)
				)
				(justify left)
			)
		)
		(duplicate_pad_numbers_are_jumpers no)
		(fp_poly
			(pts
				(arc
					(start 0.889 0)
					(mid -0.889 0)
					(end 0.889 0)
				)
			)
			(stroke
				(width 0)
				(type default)
			)
			(fill no)
			(layer "B.CrtYd")
		)
		(fp_poly
			(pts
				(arc
					(start 0.889 0)
					(mid -0.889 0)
					(end 0.889 0)
				)
			)
			(stroke
				(width 0)
				(type default)
			)
			(fill no)
			(layer "F.CrtYd")
		)
		(pad "1" thru_hole circle
			(at 0 0)
			(size 0.508 0.508)
			(drill 0.254)
			(layers "*.Cu" "*.Mask")
			(remove_unused_layers no)
			(net "UNNAMED_524_FT4232HLREELQFP64_2")
			(clearance 0.1016)
			(padstack
				(mode front_inner_back)
				(layer "Inner"
					(shape circle)
					(size 0.508 0.508)
					(clearance 0.1016)
				)
				(layer "B.Cu"
					(shape circle)
					(size 0.762 0.762)
					(clearance -0.0254)
				)
			)
		)
	)
	(footprint ""
		(layer "F.Cu")
		(at 36.83 -141.478)
		(property "Reference" "SP20"
			(at 0 0 0)
			(layer "F.SilkS")
			(hide yes)
			(effects
				(font
					(size 1.27 1.27)
				)
			)
		)
		(property "Value" ""
			(at 0 0 0)
			(layer "F.Fab")
			(effects
				(font
					(size 1.27 1.27)
				)
			)
		)
		(duplicate_pad_numbers_are_jumpers no)
	)
	(footprint ""
		(layer "F.Cu")
		(at 49.657 -126.238)
		(property "Reference" "SP68"
			(at 0 0 0)
			(layer "F.SilkS")
			(hide yes)
			(effects
				(font
					(size 1.27 1.27)
				)
			)
		)
		(property "Value" ""
			(at 0 0 0)
			(layer "F.Fab")
			(effects
				(font
					(size 1.27 1.27)
				)
			)
		)
		(duplicate_pad_numbers_are_jumpers no)
	)
)
